(kicad_pcb
	(version 20260206)
	(generator "pcbnew")
	(generator_version "10.0")
	(general
		(thickness 1.6)
		(legacy_teardrops no)
	)
	(paper "A4")
	(title_block
		(title "Wiwynn_Tioga_Pass_MB.brd")
		(comment 1 "Tioga Pass / footprints 998-1004 of 4770")
	)
	(layers
		(0 "F.Cu" signal "TOP")
		(4 "In1.Cu" signal "L2GND")
		(6 "In2.Cu" signal "L3")
		(8 "In3.Cu" signal "L4GND")
		(10 "In4.Cu" signal "L5")
		(12 "In5.Cu" signal "L6GND")
		(14 "In6.Cu" signal "L7VCC")
		(16 "In7.Cu" signal "L8VCC")
		(18 "In8.Cu" signal "L9GND")
		(20 "In9.Cu" signal "L10")
		(22 "In10.Cu" signal "L11GND")
		(24 "In11.Cu" signal "L12")
		(26 "In12.Cu" signal "L13GND")
		(2 "B.Cu" signal "BOTTOM")
		(9 "F.Adhes" user "F.Adhesive")
		(11 "B.Adhes" user "B.Adhesive")
		(13 "F.Paste" user "Package Geometry/Pastemask Top")
		(15 "B.Paste" user "Package Geometry/Pastemask Bottom")
		(5 "F.SilkS" user "Ref Des/Silkscreen Top")
		(7 "B.SilkS" user "Ref Des/Silkscreen Bottom")
		(1 "F.Mask" user "Board Geometry/Soldermask Top")
		(3 "B.Mask" user "Board Geometry/Soldermask Bottom")
		(17 "Dwgs.User" user "User.Drawings")
		(19 "Cmts.User" user "User.Comments")
		(21 "Eco1.User" user "User.Eco1")
		(23 "Eco2.User" user "User.Eco2")
		(25 "Edge.Cuts" user "Board Geometry/Outline")
		(27 "Margin" user)
		(31 "F.CrtYd" user "Package Geometry/Place Bound Top")
		(29 "B.CrtYd" user "Package Geometry/Place Bound Bottom")
		(35 "F.Fab" user "Ref Des/Assembly Top")
		(33 "B.Fab" user "Ref Des/Assembly Bottom")
	)
	(footprint ""
		(layer "F.Cu")
		(at 402.615146 -41.792652 90)
		(property "Reference" "R1T38"
			(at 0 0 90)
			(layer "F.SilkS")
			(hide yes)
			(effects
				(font
					(size 1.27 1.27)
				)
			)
		)
		(property "Value" ""
			(at 0 0 90)
			(layer "F.Fab")
			(effects
				(font
					(size 1.27 1.27)
				)
			)
		)
		(duplicate_pad_numbers_are_jumpers no)
		(fp_poly
			(pts
				(xy -0.2794 -0.1016) (xy 0.2794 -0.1016) (xy 0.2794 0.9906) (xy -0.2794 0.9906)
			)
			(stroke
				(width 0)
				(type default)
			)
			(fill no)
			(layer "F.CrtYd")
		)
		(fp_line
			(start 0.2794 -0.1016)
			(end -0.2794 -0.1016)
			(stroke
				(width 0.1)
				(type default)
			)
			(layer "F.Fab")
		)
		(fp_line
			(start -0.2794 -0.1016)
			(end -0.2794 0.9906)
			(stroke
				(width 0.1)
				(type default)
			)
			(layer "F.Fab")
		)
		(fp_line
			(start 0.2794 0.9906)
			(end 0.2794 -0.1016)
			(stroke
				(width 0.1)
				(type default)
			)
			(layer "F.Fab")
		)
		(fp_line
			(start -0.2794 0.9906)
			(end 0.2794 0.9906)
			(stroke
				(width 0.1)
				(type default)
			)
			(layer "F.Fab")
		)
		(pad "1" smd rect
			(at 0 0 90)
			(size 0.508 0.508)
			(layers "F.Cu" "F.Mask" "F.Paste")
			(net "FM_CPU1_PROCHOT_LVT3_N")
		)
		(pad "2" smd rect
			(at 0 0.889 90)
			(size 0.508 0.508)
			(layers "F.Cu" "F.Mask" "F.Paste")
			(net "FM_CPU1_PROCHOT_PCH_N")
		)
		(zone
			(layer "F.Cu")
			(hatch none 0.5)
			(connect_pads
				(clearance 0)
			)
			(min_thickness 0.25)
			(keepout
				(tracks allowed)
				(vias not_allowed)
				(pads allowed)
				(copperpour not_allowed)
				(footprints allowed)
			)
			(placement
				(enabled no)
				(sheetname "")
			)
			(fill
				(thermal_gap 0.5)
				(thermal_bridge_width 0.5)
				(island_removal_mode 0)
			)
			(polygon
				(pts
					(xy 402.869146 -41.538652) (xy 402.869146 -42.046652) (xy 403.250146 -42.046652) (xy 403.250146 -41.538652)
				)
			)
		)
		(zone
			(layer "F.Cu")
			(hatch none 0.5)
			(connect_pads
				(clearance 0)
			)
			(min_thickness 0.25)
			(keepout
				(tracks not_allowed)
				(vias allowed)
				(pads allowed)
				(copperpour not_allowed)
				(footprints allowed)
			)
			(placement
				(enabled no)
				(sheetname "")
			)
			(fill
				(thermal_gap 0.5)
				(thermal_bridge_width 0.5)
				(island_removal_mode 0)
			)
			(polygon
				(pts
					(xy 403.250146 -41.538652) (xy 403.250146 -42.046652) (xy 402.869146 -42.046652) (xy 402.869146 -41.538652)
				)
			)
		)
	)
	(footprint ""
		(layer "F.Cu")
		(at 35.028378 -121.59361)
		(property "Reference" "C1B14"
			(at -6.204966 4.045458 270)
			(unlocked yes)
			(layer "F.SilkS")
			(effects
				(font
					(size 0.7874 0.5842)
					(thickness 0.1524)
				)
			)
		)
		(property "Value" ""
			(at 0 0 0)
			(layer "F.Fab")
			(effects
				(font
					(size 1.27 1.27)
				)
			)
		)
		(duplicate_pad_numbers_are_jumpers no)
		(fp_line
			(start -5.1435 -0.127)
			(end -4.3815 -1.016)
			(stroke
				(width 0.1524)
				(type default)
			)
			(layer "F.SilkS")
		)
		(fp_line
			(start -5.1435 9.271)
			(end -5.1435 -0.127)
			(stroke
				(width 0.1524)
				(type default)
			)
			(layer "F.SilkS")
		)
		(fp_line
			(start -4.3815 -1.016)
			(end -1.8415 -1.016)
			(stroke
				(width 0.1524)
				(type default)
			)
			(layer "F.SilkS")
		)
		(fp_line
			(start -1.8415 -2.0955)
			(end -1.8415 2.0955)
			(stroke
				(width 0.1524)
				(type default)
			)
			(layer "F.SilkS")
		)
		(fp_line
			(start -1.8415 2.0955)
			(end -1.4097 2.0955)
			(stroke
				(width 0.1524)
				(type default)
			)
			(layer "F.SilkS")
		)
		(fp_line
			(start -1.4097 -2.0955)
			(end -1.8415 -2.0955)
			(stroke
				(width 0.1524)
				(type default)
			)
			(layer "F.SilkS")
		)
		(fp_line
			(start -1.4097 9.271)
			(end -5.1435 9.271)
			(stroke
				(width 0.1524)
				(type default)
			)
			(layer "F.SilkS")
		)
		(fp_line
			(start 1.4097 -2.0955)
			(end 1.8415 -2.0955)
			(stroke
				(width 0.1524)
				(type default)
			)
			(layer "F.SilkS")
		)
		(fp_line
			(start 1.8415 -2.0955)
			(end 1.8415 2.0955)
			(stroke
				(width 0.1524)
				(type default)
			)
			(layer "F.SilkS")
		)
		(fp_line
			(start 1.8415 -1.016)
			(end 4.3815 -1.016)
			(stroke
				(width 0.1524)
				(type default)
			)
			(layer "F.SilkS")
		)
		(fp_line
			(start 1.8415 2.0955)
			(end 1.4097 2.0955)
			(stroke
				(width 0.1524)
				(type default)
			)
			(layer "F.SilkS")
		)
		(fp_line
			(start 4.3815 -1.016)
			(end 5.1435 -0.127)
			(stroke
				(width 0.1524)
				(type default)
			)
			(layer "F.SilkS")
		)
		(fp_line
			(start 5.1435 -0.127)
			(end 5.1435 9.271)
			(stroke
				(width 0.1524)
				(type default)
			)
			(layer "F.SilkS")
		)
		(fp_line
			(start 5.1435 9.271)
			(end 1.4097 9.271)
			(stroke
				(width 0.1524)
				(type default)
			)
			(layer "F.SilkS")
		)
		(fp_poly
			(pts
				(xy -5.14604 -0.12954) (xy -4.38404 -1.01346) (xy 4.37896 -1.016) (xy 5.1435 -0.12954) (xy 5.14096 9.271)
				(xy -5.14604 9.27354)
			)
			(stroke
				(width 0)
				(type default)
			)
			(fill no)
			(layer "F.CrtYd")
		)
		(fp_line
			(start -5.1435 -0.127)
			(end -4.3815 -1.016)
			(stroke
				(width 0.1)
				(type default)
			)
			(layer "F.Fab")
		)
		(fp_line
			(start -5.1435 9.271)
			(end -5.1435 -0.127)
			(stroke
				(width 0.1)
				(type default)
			)
			(layer "F.Fab")
		)
		(fp_line
			(start -4.3815 -1.016)
			(end 4.3815 -1.016)
			(stroke
				(width 0.1)
				(type default)
			)
			(layer "F.Fab")
		)
		(fp_line
			(start 4.3815 -1.016)
			(end 5.1435 -0.127)
			(stroke
				(width 0.1)
				(type default)
			)
			(layer "F.Fab")
		)
		(fp_line
			(start 5.1435 -0.127)
			(end 5.1435 9.271)
			(stroke
				(width 0.1)
				(type default)
			)
			(layer "F.Fab")
		)
		(fp_line
			(start 5.1435 9.271)
			(end -5.1435 9.271)
			(stroke
				(width 0.1)
				(type default)
			)
			(layer "F.Fab")
		)
		(fp_circle
			(center 0 4.1275)
			(end 4.9911 4.1275)
			(stroke
				(width 0.1)
				(type default)
			)
			(fill no)
			(layer "F.Fab")
		)
		(pad "1" smd rect
			(at 0 0)
			(size 1.905 4.191)
			(layers "F.Cu" "F.Mask" "F.Paste")
			(net "P12V_STBY")
		)
		(pad "2" smd rect
			(at 0 8.255)
			(size 1.905 4.191)
			(layers "F.Cu" "F.Mask" "F.Paste")
			(net "GND")
		)
		(zone
			(layer "F.Cu")
			(hatch none 0.5)
			(connect_pads
				(clearance 0)
			)
			(min_thickness 0.25)
			(keepout
				(tracks allowed)
				(vias not_allowed)
				(pads allowed)
				(copperpour not_allowed)
				(footprints allowed)
			)
			(placement
				(enabled no)
				(sheetname "")
			)
			(fill
				(thermal_gap 0.5)
				(thermal_bridge_width 0.5)
				(island_removal_mode 0)
			)
			(polygon
				(pts
					(xy 29.884878 -112.32261) (xy 40.171878 -112.32261) (xy 40.171878 -121.72061) (xy 39.409878 -122.60961)
					(xy 30.646878 -122.60961) (xy 29.884878 -121.72061)
				)
			)
		)
	)
	(footprint ""
		(layer "F.Cu")
		(at 173.482 -146.939 90)
		(property "Reference" "C4A8"
			(at 0 0 90)
			(layer "F.SilkS")
			(hide yes)
			(effects
				(font
					(size 1.27 1.27)
				)
			)
		)
		(property "Value" ""
			(at 0 0 90)
			(layer "F.Fab")
			(effects
				(font
					(size 1.27 1.27)
				)
			)
		)
		(duplicate_pad_numbers_are_jumpers no)
		(fp_rect
			(start 0.3048 0.9906)
			(end -0.3048 -0.1016)
			(stroke
				(width 0)
				(type default)
			)
			(fill no)
			(layer "F.CrtYd")
		)
		(fp_line
			(start 0.3048 -0.1016)
			(end -0.3048 -0.1016)
			(stroke
				(width 0.1)
				(type default)
			)
			(layer "F.Fab")
		)
		(fp_line
			(start -0.3048 -0.1016)
			(end -0.3048 0.9906)
			(stroke
				(width 0.1)
				(type default)
			)
			(layer "F.Fab")
		)
		(fp_line
			(start 0.3048 0.9906)
			(end 0.3048 -0.1016)
			(stroke
				(width 0.1)
				(type default)
			)
			(layer "F.Fab")
		)
		(fp_line
			(start -0.3048 0.9906)
			(end 0.3048 0.9906)
			(stroke
				(width 0.1)
				(type default)
			)
			(layer "F.Fab")
		)
		(pad "1" smd rect
			(at 0 0 90)
			(size 0.508 0.508)
			(layers "F.Cu" "F.Mask" "F.Paste")
			(net "VR_PVTT_KLM_BIAS")
		)
		(pad "2" smd rect
			(at 0 0.889 90)
			(size 0.508 0.508)
			(layers "F.Cu" "F.Mask" "F.Paste")
			(net "GND")
		)
		(zone
			(layer "F.Cu")
			(hatch none 0.5)
			(connect_pads
				(clearance 0)
			)
			(min_thickness 0.25)
			(keepout
				(tracks not_allowed)
				(vias allowed)
				(pads allowed)
				(copperpour not_allowed)
				(footprints allowed)
			)
			(placement
				(enabled no)
				(sheetname "")
			)
			(fill
				(thermal_gap 0.5)
				(thermal_bridge_width 0.5)
				(island_removal_mode 0)
			)
			(polygon
				(pts
					(xy 174.117 -147.193) (xy 173.736 -147.193) (xy 173.736 -146.685) (xy 174.117 -146.685)
				)
			)
		)
		(zone
			(layer "F.Cu")
			(hatch none 0.5)
			(connect_pads
				(clearance 0)
			)
			(min_thickness 0.25)
			(keepout
				(tracks allowed)
				(vias not_allowed)
				(pads allowed)
				(copperpour not_allowed)
				(footprints allowed)
			)
			(placement
				(enabled no)
				(sheetname "")
			)
			(fill
				(thermal_gap 0.5)
				(thermal_bridge_width 0.5)
				(island_removal_mode 0)
			)
			(polygon
				(pts
					(xy 174.117 -147.193) (xy 173.736 -147.193) (xy 173.736 -146.685) (xy 174.117 -146.685)
				)
			)
		)
	)
	(footprint ""
		(layer "F.Cu")
		(at 49.4284 -86.67242)
		(property "Reference" "C1D3"
			(at 0 0 0)
			(layer "F.SilkS")
			(hide yes)
			(effects
				(font
					(size 1.27 1.27)
				)
			)
		)
		(property "Value" ""
			(at 0 0 0)
			(layer "F.Fab")
			(effects
				(font
					(size 1.27 1.27)
				)
			)
		)
		(duplicate_pad_numbers_are_jumpers no)
		(fp_poly
			(pts
				(xy -0.4953 -0.2032) (xy 0.4953 -0.2032) (xy 0.4953 1.6002) (xy -0.4953 1.6002)
			)
			(stroke
				(width 0)
				(type default)
			)
			(fill no)
			(layer "F.CrtYd")
		)
		(fp_line
			(start -0.4953 -0.2032)
			(end 0.4953 -0.2032)
			(stroke
				(width 0.1)
				(type default)
			)
			(layer "F.Fab")
		)
		(fp_line
			(start -0.4953 1.6002)
			(end -0.4953 -0.2032)
			(stroke
				(width 0.1)
				(type default)
			)
			(layer "F.Fab")
		)
		(fp_line
			(start 0.4953 -0.2032)
			(end 0.4953 1.6002)
			(stroke
				(width 0.1)
				(type default)
			)
			(layer "F.Fab")
		)
		(fp_line
			(start 0.4953 1.6002)
			(end -0.4953 1.6002)
			(stroke
				(width 0.1)
				(type default)
			)
			(layer "F.Fab")
		)
		(pad "1" smd rect
			(at 0 0)
			(size 0.762 0.889)
			(layers "F.Cu" "F.Mask" "F.Paste")
			(net "PVCCIN_CPU1")
		)
		(pad "2" smd rect
			(at 0 1.397)
			(size 0.762 0.889)
			(layers "F.Cu" "F.Mask" "F.Paste")
			(net "GND")
		)
		(zone
			(layer "F.Cu")
			(hatch none 0.5)
			(connect_pads
				(clearance 0)
			)
			(min_thickness 0.25)
			(keepout
				(tracks not_allowed)
				(vias allowed)
				(pads allowed)
				(copperpour not_allowed)
				(footprints allowed)
			)
			(placement
				(enabled no)
				(sheetname "")
			)
			(fill
				(thermal_gap 0.5)
				(thermal_bridge_width 0.5)
				(island_removal_mode 0)
			)
			(polygon
				(pts
					(xy 49.0474 -86.22792) (xy 49.8094 -86.22792) (xy 49.8094 -85.71992) (xy 49.0474 -85.71992)
				)
			)
		)
	)
	(footprint ""
		(layer "F.Cu")
		(at 183.0832 -76.3778 -90)
		(property "Reference" "R4D32"
			(at 0 0 270)
			(layer "F.SilkS")
			(hide yes)
			(effects
				(font
					(size 1.27 1.27)
				)
			)
		)
		(property "Value" ""
			(at 0 0 270)
			(layer "F.Fab")
			(effects
				(font
					(size 1.27 1.27)
				)
			)
		)
		(duplicate_pad_numbers_are_jumpers no)
		(fp_rect
			(start 0.2794 0.9906)
			(end -0.2794 -0.1016)
			(stroke
				(width 0)
				(type default)
			)
			(fill no)
			(layer "F.CrtYd")
		)
		(fp_line
			(start -0.2794 0.9906)
			(end 0.2794 0.9906)
			(stroke
				(width 0.1)
				(type default)
			)
			(layer "F.Fab")
		)
		(fp_line
			(start 0.2794 0.9906)
			(end 0.2794 -0.1016)
			(stroke
				(width 0.1)
				(type default)
			)
			(layer "F.Fab")
		)
		(fp_line
			(start -0.2794 -0.1016)
			(end -0.2794 0.9906)
			(stroke
				(width 0.1)
				(type default)
			)
			(layer "F.Fab")
		)
		(fp_line
			(start 0.2794 -0.1016)
			(end -0.2794 -0.1016)
			(stroke
				(width 0.1)
				(type default)
			)
			(layer "F.Fab")
		)
		(pad "1" smd rect
			(at 0 0 270)
			(size 0.508 0.508)
			(layers "F.Cu" "F.Mask" "F.Paste")
			(net "VR_PVCCIN_CPU0_AVINSEN")
		)
		(pad "2" smd rect
			(at 0 0.889 270)
			(size 0.508 0.508)
			(layers "F.Cu" "F.Mask" "F.Paste")
			(net "GND")
		)
		(zone
			(layer "F.Cu")
			(hatch none 0.5)
			(connect_pads
				(clearance 0)
			)
			(min_thickness 0.25)
			(keepout
				(tracks allowed)
				(vias not_allowed)
				(pads allowed)
				(copperpour not_allowed)
				(footprints allowed)
			)
			(placement
				(enabled no)
				(sheetname "")
			)
			(fill
				(thermal_gap 0.5)
				(thermal_bridge_width 0.5)
				(island_removal_mode 0)
			)
			(polygon
				(pts
					(xy 182.4482 -76.1238) (xy 182.8292 -76.1238) (xy 182.8292 -76.6318) (xy 182.4482 -76.6318)
				)
			)
		)
		(zone
			(layer "F.Cu")
			(hatch none 0.5)
			(connect_pads
				(clearance 0)
			)
			(min_thickness 0.25)
			(keepout
				(tracks not_allowed)
				(vias allowed)
				(pads allowed)
				(copperpour not_allowed)
				(footprints allowed)
			)
			(placement
				(enabled no)
				(sheetname "")
			)
			(fill
				(thermal_gap 0.5)
				(thermal_bridge_width 0.5)
				(island_removal_mode 0)
			)
			(polygon
				(pts
					(xy 182.4482 -76.1238) (xy 182.8292 -76.1238) (xy 182.8292 -76.6318) (xy 182.4482 -76.6318)
				)
			)
		)
	)
	(footprint ""
		(layer "F.Cu")
		(at 162.306 -64.8716 90)
		(property "Reference" "SH3D2"
			(at 0 0 90)
			(layer "F.SilkS")
			(hide yes)
			(effects
				(font
					(size 1.27 1.27)
				)
			)
		)
		(property "Value" ""
			(at 0 0 90)
			(layer "F.Fab")
			(effects
				(font
					(size 1.27 1.27)
				)
			)
		)
		(duplicate_pad_numbers_are_jumpers no)
		(fp_poly
			(pts
				(xy -0.1651 -0.0508) (xy -0.1651 0.5842) (xy 0.1651 0.5842) (xy 0.1651 -0.0508)
			)
			(stroke
				(width 0)
				(type default)
			)
			(fill no)
			(layer "F.CrtYd")
		)
		(fp_line
			(start 0.1651 -0.0508)
			(end 0.1651 0.5842)
			(stroke
				(width 0.1)
				(type default)
			)
			(layer "F.Fab")
		)
		(fp_line
			(start -0.1651 -0.0508)
			(end 0.1651 -0.0508)
			(stroke
				(width 0.1)
				(type default)
			)
			(layer "F.Fab")
		)
		(fp_line
			(start 0.1651 0.5842)
			(end -0.1651 0.5842)
			(stroke
				(width 0.1)
				(type default)
			)
			(layer "F.Fab")
		)
		(fp_line
			(start -0.1651 0.5842)
			(end -0.1651 -0.0508)
			(stroke
				(width 0.1)
				(type default)
			)
			(layer "F.Fab")
		)
		(pad "1" smd custom
			(at 0 0 270)
			(size 0.0762 0.0762)
			(layers "F.Cu" "F.Mask" "F.Paste")
			(net "VSENSE_PVCCIO_CPU1_SKT_VSEN")
			(options
				(clearance outline)
				(anchor circle)
			)
			(primitives
				(gr_poly
					(pts
						(arc
							(start -0.1524 -0.10795)
							(mid -0.098518 -0.130268)
							(end -0.0762 -0.18415)
						)
						(xy -0.0762 -0.22225) (xy 0.0762 -0.22225)
						(arc
							(start 0.0762 -0.18415)
							(mid 0.098518 -0.130268)
							(end 0.1524 -0.10795)
						)
						(xy 0.1524 0.22225) (xy -0.1524 0.22225)
					)
					(width 0)
					(fill yes)
				)
			)
		)
		(pad "2" smd custom
			(at 0 0.5334 90)
			(size 0.0762 0.0762)
			(layers "F.Cu" "F.Mask" "F.Paste")
			(net "VSENSE_PVCCIO_CPU1_AVSP")
			(options
				(clearance outline)
				(anchor circle)
			)
			(primitives
				(gr_poly
					(pts
						(arc
							(start -0.1524 -0.10795)
							(mid -0.098518 -0.130268)
							(end -0.0762 -0.18415)
						)
						(xy -0.0762 -0.22225) (xy 0.0762 -0.22225)
						(arc
							(start 0.0762 -0.18415)
							(mid 0.098518 -0.130268)
							(end 0.1524 -0.10795)
						)
						(xy 0.1524 0.22225) (xy -0.1524 0.22225)
					)
					(width 0)
					(fill yes)
				)
			)
		)
	)
	(footprint ""
		(layer "F.Cu")
		(at 481.369624 -24.552148 -90)
		(property "Reference" "FB9E1"
			(at 0 0 270)
			(layer "F.SilkS")
			(hide yes)
			(effects
				(font
					(size 1.27 1.27)
				)
			)
		)
		(property "Value" "*"
			(at -2.4511 -3.44805 270)
			(unlocked yes)
			(layer "F.Fab")
			(hide yes)
			(effects
				(font
					(size 0.889 0.889)
					(thickness 0.1524)
				)
			)
		)
		(property "Device Type" "BLM31SN500SN1L-GP_DISCRET-GB1-A"
			(at -2.4511 -4.97205 270)
			(unlocked yes)
			(layer "F.Fab")
			(hide yes)
			(effects
				(font
					(size 0.889 0.889)
					(thickness 0.1524)
				)
			)
		)
		(duplicate_pad_numbers_are_jumpers no)
		(fp_line
			(start -1.27 2.2352)
			(end -1.27 -2.2352)
			(stroke
				(width 0.1524)
				(type default)
			)
			(layer "F.SilkS")
		)
		(fp_line
			(start 1.27 2.2352)
			(end -1.27 2.2352)
			(stroke
				(width 0.1524)
				(type default)
			)
			(layer "F.SilkS")
		)
		(fp_line
			(start -1.27 -2.2352)
			(end 1.27 -2.2352)
			(stroke
				(width 0.1524)
				(type default)
			)
			(layer "F.SilkS")
		)
		(fp_line
			(start 1.27 -2.2352)
			(end 1.27 2.2352)
			(stroke
				(width 0.1524)
				(type default)
			)
			(layer "F.SilkS")
		)
		(fp_rect
			(start -0.8001 1.6002)
			(end 0.8001 -1.6002)
			(stroke
				(width 0)
				(type default)
			)
			(fill no)
			(layer "F.CrtYd")
		)
		(fp_poly
			(pts
				(xy -0.8001 -1.6002) (xy 1.524 -1.6002) (xy 1.524 -2.3114) (xy -1.524 -2.3114) (xy -1.524 2.3114)
				(xy 1.524 2.3114) (xy 1.524 -1.5875) (xy 0.8001 -1.5875) (xy 0.8001 1.6002) (xy -0.8001 1.6002)
			)
			(stroke
				(width 0)
				(type default)
			)
			(fill no)
			(layer "F.CrtYd")
		)
		(fp_rect
			(start -1.524 2.3114)
			(end 1.524 -2.3114)
			(stroke
				(width 0)
				(type default)
			)
			(fill no)
			(layer "F.Fab")
		)
		(pad "1" smd rect
			(at 0 -1.5367 270)
			(size 2.032 1.397)
			(drill
				(offset 0 0.2032)
			)
			(layers "F.Cu" "F.Mask" "F.Paste")
			(net "P12V_STBY")
		)
		(pad "2" smd rect
			(at 0 1.5367 270)
			(size 2.032 1.397)
			(drill
				(offset 0 -0.2032)
			)
			(layers "F.Cu" "F.Mask" "F.Paste")
			(net "VR_FET_SW_P12V_STBY_P3V3_STBY")
		)
	)
)
